# S9S_MB_2U (Grand Teton) — schematic netlist excerpt (pin names and nets, part order shuffled) for the footprints in the layout excerpt that follows; sources: Cadence DE-HDL packaged netlist, KiCad conversion of 03242023_DA0F0TMBIJ0_F0T_Motherboard_J_brd_V01_OCP.brd

C1236  Q_CAP  0.1UF 25V 10% X7R  pkg 0402  page 153 : A = P12V_OCP_SFF ; B = GND
R4393  Q_RES  33.2 1% CHIP  pkg 0402LF  page 225 : A = H_CPU_ERR1_LVC2_R_N ; B = H_CPU_ERR1_PCH_R_N

(kicad_pcb
	(version 20260206)
	(generator "pcbnew")
	(generator_version "10.0")
	(general
		(thickness 1.6)
		(legacy_teardrops no)
	)
	(paper "A4")
	(title_block
		(title "03242023_DA0F0TMBIJ0_F0T_Motherboard_J_brd_V01_OCP.brd")
		(comment 1 "Grand Teton / footprints 2543-2544 of 6105")
	)
	(layers
		(0 "F.Cu" signal "TOP")
		(4 "In1.Cu" signal "GND")
		(6 "In2.Cu" signal "IN1")
		(8 "In3.Cu" signal "GND1")
		(10 "In4.Cu" signal "IN2")
		(12 "In5.Cu" signal "GND2")
		(14 "In6.Cu" signal "IN3")
		(16 "In7.Cu" signal "GND3")
		(18 "In8.Cu" signal "VCC")
		(20 "In9.Cu" signal "VCC1")
		(22 "In10.Cu" signal "GND4")
		(24 "In11.Cu" signal "IN4")
		(26 "In12.Cu" signal "GND5")
		(28 "In13.Cu" signal "IN5")
		(30 "In14.Cu" signal "GND6")
		(32 "In15.Cu" signal "IN6")
		(34 "In16.Cu" signal "GND7")
		(2 "B.Cu" signal "BOTTOM")
		(9 "F.Adhes" user "F.Adhesive")
		(11 "B.Adhes" user "B.Adhesive")
		(13 "F.Paste" user "Package Geometry/Pastemask Top")
		(15 "B.Paste" user "Package Geometry/Pastemask Bottom")
		(5 "F.SilkS" user "Ref Des/Silkscreen Top")
		(7 "B.SilkS" user "Ref Des/Silkscreen Bottom")
		(1 "F.Mask" user "Board Geometry/Soldermask Top")
		(3 "B.Mask" user "Board Geometry/Soldermask Bottom")
		(17 "Dwgs.User" user "User.Drawings")
		(19 "Cmts.User" user "User.Comments")
		(21 "Eco1.User" user "User.Eco1")
		(23 "Eco2.User" user "User.Eco2")
		(25 "Edge.Cuts" user "Board Geometry/Outline")
		(27 "Margin" user)
		(31 "F.CrtYd" user "Package Geometry/Place Bound Top")
		(29 "B.CrtYd" user "Package Geometry/Place Bound Bottom")
		(35 "F.Fab" user "Ref Des/Assembly Top")
		(33 "B.Fab" user "Ref Des/Assembly Bottom")
	)
	(footprint ""
		(layer "F.Cu")
		(at 440.395868 -16.700246 180)
		(property "Reference" "C1236"
			(at 0 0 180)
			(layer "F.SilkS")
			(hide yes)
			(effects
				(font
					(size 1.27 1.27)
				)
			)
		)
		(property "Value" ""
			(at 0 0 180)
			(layer "F.Fab")
			(effects
				(font
					(size 1.27 1.27)
				)
			)
		)
		(duplicate_pad_numbers_are_jumpers no)
		(fp_line
			(start 0.7874 0.4064)
			(end -0.7874 0.4064)
			(stroke
				(width 0.1524)
				(type default)
			)
			(layer "F.SilkS")
		)
		(fp_line
			(start 0.7874 -0.4064)
			(end 0.7874 0.4064)
			(stroke
				(width 0.1524)
				(type default)
			)
			(layer "F.SilkS")
		)
		(fp_line
			(start -0.7874 0.4064)
			(end -0.7874 -0.4064)
			(stroke
				(width 0.1524)
				(type default)
			)
			(layer "F.SilkS")
		)
		(fp_line
			(start -0.7874 -0.4064)
			(end 0.7874 -0.4064)
			(stroke
				(width 0.1524)
				(type default)
			)
			(layer "F.SilkS")
		)
		(fp_line
			(start 0.67945 0.3048)
			(end 0.120396 0.3048)
			(stroke
				(width 0.1)
				(type default)
			)
			(layer "F.Fab")
		)
		(fp_line
			(start 0.67945 -0.3048)
			(end 0.67945 0.3048)
			(stroke
				(width 0.1)
				(type default)
			)
			(layer "F.Fab")
		)
		(fp_line
			(start 0.12065 -0.2794)
			(end 0.12065 -0.3048)
			(stroke
				(width 0.1)
				(type default)
			)
			(layer "F.Fab")
		)
		(fp_line
			(start 0.12065 -0.3048)
			(end 0.67945 -0.3048)
			(stroke
				(width 0.1)
				(type default)
			)
			(layer "F.Fab")
		)
		(fp_line
			(start 0.120396 0.3048)
			(end 0.120396 0.2794)
			(stroke
				(width 0.1)
				(type default)
			)
			(layer "F.Fab")
		)
		(fp_line
			(start 0.120396 0.2794)
			(end -0.12065 0.2794)
			(stroke
				(width 0.1)
				(type default)
			)
			(layer "F.Fab")
		)
		(fp_line
			(start -0.12065 0.3048)
			(end -0.67945 0.3048)
			(stroke
				(width 0.1)
				(type default)
			)
			(layer "F.Fab")
		)
		(fp_line
			(start -0.12065 0.2794)
			(end -0.12065 0.3048)
			(stroke
				(width 0.1)
				(type default)
			)
			(layer "F.Fab")
		)
		(fp_line
			(start -0.12065 -0.2794)
			(end 0.12065 -0.2794)
			(stroke
				(width 0.1)
				(type default)
			)
			(layer "F.Fab")
		)
		(fp_line
			(start -0.12065 -0.305054)
			(end -0.12065 -0.2794)
			(stroke
				(width 0.1)
				(type default)
			)
			(layer "F.Fab")
		)
		(fp_line
			(start -0.67945 0.3048)
			(end -0.67945 -0.305054)
			(stroke
				(width 0.1)
				(type default)
			)
			(layer "F.Fab")
		)
		(fp_line
			(start -0.67945 -0.305054)
			(end -0.12065 -0.305054)
			(stroke
				(width 0.1)
				(type default)
			)
			(layer "F.Fab")
		)
		(pad "1" smd circle
			(at -0.40005 0 180)
			(size 0 0)
			(layers "F.Cu" "F.Mask" "F.Paste")
			(net "P12V_OCP_SFF")
		)
		(pad "2" smd circle
			(at 0.40005 0 180)
			(size 0 0)
			(layers "F.Cu" "F.Mask" "F.Paste")
			(net "GND")
		)
	)
	(footprint ""
		(layer "F.Cu")
		(at 143.433292 -92.634308 -90)
		(property "Reference" "R4393"
			(at 0 0 270)
			(layer "F.SilkS")
			(hide yes)
			(effects
				(font
					(size 1.27 1.27)
				)
			)
		)
		(property "Value" ""
			(at 0 0 270)
			(layer "F.Fab")
			(effects
				(font
					(size 1.27 1.27)
				)
			)
		)
		(duplicate_pad_numbers_are_jumpers no)
		(fp_line
			(start -0.7874 0.4064)
			(end -0.7874 -0.4064)
			(stroke
				(width 0.1524)
				(type default)
			)
			(layer "F.SilkS")
		)
		(fp_line
			(start 0.7874 0.4064)
			(end -0.7874 0.4064)
			(stroke
				(width 0.1524)
				(type default)
			)
			(layer "F.SilkS")
		)
		(fp_line
			(start -0.7874 -0.4064)
			(end 0.7874 -0.4064)
			(stroke
				(width 0.1524)
				(type default)
			)
			(layer "F.SilkS")
		)
		(fp_line
			(start 0.7874 -0.4064)
			(end 0.7874 0.4064)
			(stroke
				(width 0.1524)
				(type default)
			)
			(layer "F.SilkS")
		)
		(fp_line
			(start -0.67945 0.3048)
			(end -0.67945 -0.305054)
			(stroke
				(width 0.1)
				(type default)
			)
			(layer "F.Fab")
		)
		(fp_line
			(start -0.12065 0.3048)
			(end -0.67945 0.3048)
			(stroke
				(width 0.1)
				(type default)
			)
			(layer "F.Fab")
		)
		(fp_line
			(start 0.120396 0.3048)
			(end 0.120396 0.2794)
			(stroke
				(width 0.1)
				(type default)
			)
			(layer "F.Fab")
		)
		(fp_line
			(start 0.67945 0.3048)
			(end 0.120396 0.3048)
			(stroke
				(width 0.1)
				(type default)
			)
			(layer "F.Fab")
		)
		(fp_line
			(start -0.12065 0.2794)
			(end -0.12065 0.3048)
			(stroke
				(width 0.1)
				(type default)
			)
			(layer "F.Fab")
		)
		(fp_line
			(start 0.120396 0.2794)
			(end -0.12065 0.2794)
			(stroke
				(width 0.1)
				(type default)
			)
			(layer "F.Fab")
		)
		(fp_line
			(start -0.12065 -0.2794)
			(end 0.12065 -0.2794)
			(stroke
				(width 0.1)
				(type default)
			)
			(layer "F.Fab")
		)
		(fp_line
			(start 0.12065 -0.2794)
			(end 0.12065 -0.3048)
			(stroke
				(width 0.1)
				(type default)
			)
			(layer "F.Fab")
		)
		(fp_line
			(start 0.12065 -0.3048)
			(end 0.67945 -0.3048)
			(stroke
				(width 0.1)
				(type default)
			)
			(layer "F.Fab")
		)
		(fp_line
			(start 0.67945 -0.3048)
			(end 0.67945 0.3048)
			(stroke
				(width 0.1)
				(type default)
			)
			(layer "F.Fab")
		)
		(fp_line
			(start -0.67945 -0.305054)
			(end -0.12065 -0.305054)
			(stroke
				(width 0.1)
				(type default)
			)
			(layer "F.Fab")
		)
		(fp_line
			(start -0.12065 -0.305054)
			(end -0.12065 -0.2794)
			(stroke
				(width 0.1)
				(type default)
			)
			(layer "F.Fab")
		)
		(pad "1" smd circle
			(at -0.40005 0 270)
			(size 0 0)
			(layers "F.Cu" "F.Mask" "F.Paste")
			(net "H_CPU_ERR1_LVC2_R_N")
		)
		(pad "2" smd circle
			(at 0.40005 0 270)
			(size 0 0)
			(layers "F.Cu" "F.Mask" "F.Paste")
			(net "H_CPU_ERR1_PCH_R_N")
		)
	)
)
